# S9S_MB_2U (Grand Teton) — schematic netlist excerpt (pin names and nets, part order shuffled) for the footprints in the layout excerpt that follows; sources: Cadence DE-HDL packaged netlist, KiCad conversion of 03242023_DA0F0TMBIJ0_F0T_Motherboard_J_brd_V01_OCP.brd

C1122  Q_CAP  0.1UF 25V 10% X7R  pkg 0402  page 217 : A = P3V3_AUX_FPGA_VCCIO2 ; B = GND
R2357  Q_RES  10K 1% CHIP  pkg 0402LF  page 262 : A = P3V3_AUX ; B = PWRGD_P1V05_PCH_AUX_R

(kicad_pcb
	(version 20260206)
	(generator "pcbnew")
	(generator_version "10.0")
	(general
		(thickness 1.6)
		(legacy_teardrops no)
	)
	(paper "A4")
	(title_block
		(title "03242023_DA0F0TMBIJ0_F0T_Motherboard_J_brd_V01_OCP.brd")
		(comment 1 "Grand Teton / footprints 4418-4419 of 6105")
	)
	(layers
		(0 "F.Cu" signal "TOP")
		(4 "In1.Cu" signal "GND")
		(6 "In2.Cu" signal "IN1")
		(8 "In3.Cu" signal "GND1")
		(10 "In4.Cu" signal "IN2")
		(12 "In5.Cu" signal "GND2")
		(14 "In6.Cu" signal "IN3")
		(16 "In7.Cu" signal "GND3")
		(18 "In8.Cu" signal "VCC")
		(20 "In9.Cu" signal "VCC1")
		(22 "In10.Cu" signal "GND4")
		(24 "In11.Cu" signal "IN4")
		(26 "In12.Cu" signal "GND5")
		(28 "In13.Cu" signal "IN5")
		(30 "In14.Cu" signal "GND6")
		(32 "In15.Cu" signal "IN6")
		(34 "In16.Cu" signal "GND7")
		(2 "B.Cu" signal "BOTTOM")
		(9 "F.Adhes" user "F.Adhesive")
		(11 "B.Adhes" user "B.Adhesive")
		(13 "F.Paste" user "Package Geometry/Pastemask Top")
		(15 "B.Paste" user "Package Geometry/Pastemask Bottom")
		(5 "F.SilkS" user "Ref Des/Silkscreen Top")
		(7 "B.SilkS" user "Ref Des/Silkscreen Bottom")
		(1 "F.Mask" user "Board Geometry/Soldermask Top")
		(3 "B.Mask" user "Board Geometry/Soldermask Bottom")
		(17 "Dwgs.User" user "User.Drawings")
		(19 "Cmts.User" user "User.Comments")
		(21 "Eco1.User" user "User.Eco1")
		(23 "Eco2.User" user "User.Eco2")
		(25 "Edge.Cuts" user "Board Geometry/Outline")
		(27 "Margin" user)
		(31 "F.CrtYd" user "Package Geometry/Place Bound Top")
		(29 "B.CrtYd" user "Package Geometry/Place Bound Bottom")
		(35 "F.Fab" user "Ref Des/Assembly Top")
		(33 "B.Fab" user "Ref Des/Assembly Bottom")
	)
	(footprint ""
		(layer "B.Cu")
		(at 257.48488 -78.577948 90)
		(property "Reference" "R2357"
			(at 0 0 90)
			(layer "B.SilkS")
			(hide yes)
			(effects
				(font
					(size 1.27 1.27)
				)
				(justify mirror)
			)
		)
		(property "Value" ""
			(at 0 0 90)
			(layer "B.Fab")
			(effects
				(font
					(size 1.27 1.27)
				)
				(justify mirror)
			)
		)
		(duplicate_pad_numbers_are_jumpers no)
		(fp_line
			(start 0.7874 -0.4064)
			(end -0.7874 -0.4064)
			(stroke
				(width 0.1524)
				(type default)
			)
			(layer "B.SilkS")
		)
		(fp_line
			(start -0.7874 -0.4064)
			(end -0.7874 0.4064)
			(stroke
				(width 0.1524)
				(type default)
			)
			(layer "B.SilkS")
		)
		(fp_line
			(start 0.7874 0.4064)
			(end 0.7874 -0.4064)
			(stroke
				(width 0.1524)
				(type default)
			)
			(layer "B.SilkS")
		)
		(fp_line
			(start -0.7874 0.4064)
			(end 0.7874 0.4064)
			(stroke
				(width 0.1524)
				(type default)
			)
			(layer "B.SilkS")
		)
		(fp_line
			(start 0.67945 -0.305054)
			(end 0.12065 -0.305054)
			(stroke
				(width 0.1)
				(type default)
			)
			(layer "B.Fab")
		)
		(fp_line
			(start 0.12065 -0.305054)
			(end 0.12065 -0.2794)
			(stroke
				(width 0.1)
				(type default)
			)
			(layer "B.Fab")
		)
		(fp_line
			(start -0.12065 -0.3048)
			(end -0.67945 -0.3048)
			(stroke
				(width 0.1)
				(type default)
			)
			(layer "B.Fab")
		)
		(fp_line
			(start -0.67945 -0.3048)
			(end -0.67945 0.3048)
			(stroke
				(width 0.1)
				(type default)
			)
			(layer "B.Fab")
		)
		(fp_line
			(start 0.12065 -0.2794)
			(end -0.12065 -0.2794)
			(stroke
				(width 0.1)
				(type default)
			)
			(layer "B.Fab")
		)
		(fp_line
			(start -0.12065 -0.2794)
			(end -0.12065 -0.3048)
			(stroke
				(width 0.1)
				(type default)
			)
			(layer "B.Fab")
		)
		(fp_line
			(start 0.12065 0.2794)
			(end 0.12065 0.3048)
			(stroke
				(width 0.1)
				(type default)
			)
			(layer "B.Fab")
		)
		(fp_line
			(start -0.120396 0.2794)
			(end 0.12065 0.2794)
			(stroke
				(width 0.1)
				(type default)
			)
			(layer "B.Fab")
		)
		(fp_line
			(start 0.67945 0.3048)
			(end 0.67945 -0.305054)
			(stroke
				(width 0.1)
				(type default)
			)
			(layer "B.Fab")
		)
		(fp_line
			(start 0.12065 0.3048)
			(end 0.67945 0.3048)
			(stroke
				(width 0.1)
				(type default)
			)
			(layer "B.Fab")
		)
		(fp_line
			(start -0.120396 0.3048)
			(end -0.120396 0.2794)
			(stroke
				(width 0.1)
				(type default)
			)
			(layer "B.Fab")
		)
		(fp_line
			(start -0.67945 0.3048)
			(end -0.120396 0.3048)
			(stroke
				(width 0.1)
				(type default)
			)
			(layer "B.Fab")
		)
		(pad "1" smd circle
			(at 0.40005 0 270)
			(size 0 0)
			(layers "B.Cu" "B.Mask" "B.Paste")
			(net "P3V3_AUX")
		)
		(pad "2" smd circle
			(at -0.40005 0 270)
			(size 0 0)
			(layers "B.Cu" "B.Mask" "B.Paste")
			(net "PWRGD_P1V05_PCH_AUX_R")
		)
	)
	(footprint ""
		(layer "B.Cu")
		(at 181.755542 -112.97539)
		(property "Reference" "C1122"
			(at 0 0 0)
			(layer "B.SilkS")
			(hide yes)
			(effects
				(font
					(size 1.27 1.27)
				)
				(justify mirror)
			)
		)
		(property "Value" ""
			(at 0 0 0)
			(layer "B.Fab")
			(effects
				(font
					(size 1.27 1.27)
				)
				(justify mirror)
			)
		)
		(duplicate_pad_numbers_are_jumpers no)
		(fp_line
			(start -0.69215 -0.2921)
			(end -0.69215 0.2921)
			(stroke
				(width 0.1524)
				(type default)
			)
			(layer "B.SilkS")
		)
		(fp_line
			(start -0.69215 0.2921)
			(end 0.69215 0.2921)
			(stroke
				(width 0.1524)
				(type default)
			)
			(layer "B.SilkS")
		)
		(fp_line
			(start 0.69215 -0.2921)
			(end -0.69215 -0.2921)
			(stroke
				(width 0.1524)
				(type default)
			)
			(layer "B.SilkS")
		)
		(fp_line
			(start 0.69215 0.2921)
			(end 0.69215 -0.2921)
			(stroke
				(width 0.1524)
				(type default)
			)
			(layer "B.SilkS")
		)
		(fp_line
			(start -0.51435 -0.2794)
			(end -0.51435 0.2794)
			(stroke
				(width 0.1)
				(type default)
			)
			(layer "B.Fab")
		)
		(fp_line
			(start -0.51435 0.2794)
			(end 0.51435 0.2794)
			(stroke
				(width 0.1)
				(type default)
			)
			(layer "B.Fab")
		)
		(fp_line
			(start 0.51435 -0.2794)
			(end -0.51435 -0.2794)
			(stroke
				(width 0.1)
				(type default)
			)
			(layer "B.Fab")
		)
		(fp_line
			(start 0.51435 0.2794)
			(end 0.51435 -0.2794)
			(stroke
				(width 0.1)
				(type default)
			)
			(layer "B.Fab")
		)
		(pad "1" smd circle
			(at 0.40005 0 180)
			(size 0 0)
			(layers "B.Cu" "B.Mask" "B.Paste")
			(net "P3V3_AUX_FPGA_VCCIO2")
		)
		(pad "2" smd circle
			(at -0.40005 0 180)
			(size 0 0)
			(layers "B.Cu" "B.Mask" "B.Paste")
			(net "GND")
		)
		(zone
			(layer "B.Cu")
			(hatch none 0.5)
			(connect_pads
				(clearance 0)
			)
			(min_thickness 0.25)
			(keepout
				(tracks not_allowed)
				(vias allowed)
				(pads allowed)
				(copperpour not_allowed)
				(footprints allowed)
			)
			(placement
				(enabled no)
				(sheetname "")
			)
			(fill
				(thermal_gap 0.5)
				(thermal_bridge_width 0.5)
				(island_removal_mode 0)
			)
			(polygon
				(pts
					(xy 181.946042 -112.88776) (xy 181.854602 -112.829594) (xy 181.655212 -112.829594) (xy 181.565042 -112.88776)
					(xy 181.565042 -113.06302) (xy 181.655212 -113.12144) (xy 181.854602 -113.12144) (xy 181.946042 -113.063274)
				)
			)
		)
	)
)
